(kicad_pcb
	(version 20241229)
	(generator "pcbnew")
	(generator_version "9.0")
	(general
		(thickness 1.294)
		(legacy_teardrops no)
	)
	(paper "A3")
	(title_block
		(title "Kintex 410T devboard")
		(date "2024-04-03")
		(rev "1.1.2")
		(comment 9 "footprints 132-135 of 975")
	)
	(layers
		(0 "F.Cu" mixed)
		(4 "In1.Cu" power)
		(6 "In2.Cu" power)
		(8 "In3.Cu" mixed)
		(10 "In4.Cu" power)
		(12 "In5.Cu" mixed)
		(14 "In6.Cu" power)
		(16 "In7.Cu" mixed)
		(18 "In8.Cu" power)
		(2 "B.Cu" mixed)
		(9 "F.Adhes" user "F.Adhesive")
		(11 "B.Adhes" user "B.Adhesive")
		(13 "F.Paste" user)
		(15 "B.Paste" user)
		(5 "F.SilkS" user "F.Silkscreen")
		(7 "B.SilkS" user "B.Silkscreen")
		(1 "F.Mask" user)
		(3 "B.Mask" user)
		(17 "Dwgs.User" user "User.Drawings")
		(19 "Cmts.User" user "User.Comments")
		(21 "Eco1.User" user "User.Eco1")
		(23 "Eco2.User" user "User.Eco2")
		(25 "Edge.Cuts" user)
		(27 "Margin" user)
		(31 "F.CrtYd" user "F.Courtyard")
		(29 "B.CrtYd" user "B.Courtyard")
		(35 "F.Fab" user)
		(33 "B.Fab" user)
	)
	(footprint "antmicro-footprints:C_0402_1005Metric"
		(layer "F.Cu")
		(at 173.570001 117.557501 180)
		(descr "Capacitor SMD 0402")
		(tags "capacitor SMD 0402")
		(property "Reference" "C304"
			(at -3.729999 -0.342499 0)
			(layer "F.SilkS")
			(effects
				(font
					(size 0.7 0.7)
					(thickness 0.15)
				)
				(justify right bottom)
			)
		)
		(property "Value" "C_100n_0402"
			(at 0 1.4 0)
			(layer "F.Fab")
			(effects
				(font
					(size 0.7 0.7)
					(thickness 0.15)
				)
				(justify right bottom)
			)
		)
		(property "Description" "SMD Multilayer Ceramic Capacitor, 0.1 µF, 50 V, 0402 [1005 Metric], ± 10%, X5R, GRM Series"
			(at 0 0 180)
			(layer "F.Fab")
			(hide yes)
			(effects
				(font
					(size 1.27 1.27)
					(thickness 0.15)
				)
			)
		)
		(property "Author" "Antmicro"
			(at 347.140002 235.115002 0)
			(layer "F.Fab")
			(hide yes)
			(effects
				(font
					(size 1 1)
					(thickness 0.15)
				)
			)
		)
		(property "Dielectric" "X5R"
			(at 347.140002 235.115002 0)
			(layer "F.Fab")
			(hide yes)
			(effects
				(font
					(size 1 1)
					(thickness 0.15)
				)
			)
		)
		(property "License" "Apache-2.0"
			(at 347.140002 235.115002 0)
			(layer "F.Fab")
			(hide yes)
			(effects
				(font
					(size 1 1)
					(thickness 0.15)
				)
			)
		)
		(property "MPN" "GRM155R61H104KE14D"
			(at 347.140002 235.115002 0)
			(layer "F.Fab")
			(hide yes)
			(effects
				(font
					(size 1 1)
					(thickness 0.15)
				)
			)
		)
		(property "Manufacturer" "Murata"
			(at 347.140002 235.115002 0)
			(layer "F.Fab")
			(hide yes)
			(effects
				(font
					(size 1 1)
					(thickness 0.15)
				)
			)
		)
		(property "Val" "100n"
			(at 347.140002 235.115002 0)
			(layer "F.Fab")
			(hide yes)
			(effects
				(font
					(size 1 1)
					(thickness 0.15)
				)
			)
		)
		(property "Voltage" "50V"
			(at 347.140002 235.115002 0)
			(layer "F.Fab")
			(hide yes)
			(effects
				(font
					(size 1 1)
					(thickness 0.15)
				)
			)
		)
		(sheetname "FMC+ HSPC")
		(sheetfile "fmc-hspc.kicad_sch")
		(attr smd)
		(fp_rect
			(start -0.925 -0.47)
			(end 0.925 0.47)
			(stroke
				(width 0.05)
				(type default)
			)
			(fill no)
			(layer "F.CrtYd")
		)
		(fp_line
			(start 0.504 0.248)
			(end -0.494 0.248)
			(stroke
				(width 0.15)
				(type solid)
			)
			(layer "F.Fab")
		)
		(fp_line
			(start 0.504 -0.25)
			(end 0.504 0.248)
			(stroke
				(width 0.15)
				(type solid)
			)
			(layer "F.Fab")
		)
		(fp_line
			(start -0.494 0.248)
			(end -0.494 -0.25)
			(stroke
				(width 0.15)
				(type solid)
			)
			(layer "F.Fab")
		)
		(fp_line
			(start -0.494 -0.25)
			(end 0.504 -0.25)
			(stroke
				(width 0.15)
				(type solid)
			)
			(layer "F.Fab")
		)
		(pad "1" smd roundrect
			(at -0.48 0 180)
			(size 0.59 0.64)
			(layers "F.Cu" "F.Mask" "F.Paste")
			(roundrect_rratio 0.25)
			(net 80 "/FMC+ HSPC/GTX116.TX0_P")
			(pintype "passive")
		)
		(pad "2" smd roundrect
			(at 0.48 0 180)
			(size 0.59 0.64)
			(layers "F.Cu" "F.Mask" "F.Paste")
			(roundrect_rratio 0.25)
			(net 79 "/FMC+ HSPC/GTX_TX3_C_P")
			(pintype "passive")
		)
	)
	(footprint "antmicro-footprints:R_Array_4x0201_Panasonic_EXB18V"
		(layer "F.Cu")
		(at 245.4 122)
		(property "Reference" "R24"
			(at 0.85 -0.75 0)
			(layer "F.SilkS")
			(effects
				(font
					(size 0.7 0.7)
					(thickness 0.15)
				)
				(justify right bottom)
			)
		)
		(property "Value" "R_4x33R_0201_array"
			(at -1.1 1.8 0)
			(layer "F.Fab")
			(effects
				(font
					(size 0.7 0.7)
					(thickness 0.15)
				)
				(justify left bottom)
			)
		)
		(property "Description" "Fixed Network Resistor, 33 ohm, Isolated, 4 Resistors, 0502 [1406 Metric], Flat, ± 5%"
			(at 0 0 0)
			(layer "F.Fab")
			(hide yes)
			(effects
				(font
					(size 1.27 1.27)
					(thickness 0.15)
				)
			)
		)
		(property "Author" "Antmicro"
			(at 0 0 0)
			(layer "F.Fab")
			(hide yes)
			(effects
				(font
					(size 1 1)
					(thickness 0.15)
				)
			)
		)
		(property "License" "Apache-2.0"
			(at 0 0 0)
			(layer "F.Fab")
			(hide yes)
			(effects
				(font
					(size 1 1)
					(thickness 0.15)
				)
			)
		)
		(property "MPN" "EXB-18V330JX"
			(at 0 0 0)
			(layer "F.Fab")
			(hide yes)
			(effects
				(font
					(size 1 1)
					(thickness 0.15)
				)
			)
		)
		(property "Manufacturer" "Panasonic"
			(at 0 0 0)
			(layer "F.Fab")
			(hide yes)
			(effects
				(font
					(size 1 1)
					(thickness 0.15)
				)
			)
		)
		(property "Val" "R_4x33R_0201"
			(at 0 0 0)
			(layer "F.Fab")
			(hide yes)
			(effects
				(font
					(size 1 1)
					(thickness 0.15)
				)
			)
		)
		(sheetname "Supervisior MCU")
		(sheetfile "supervisor-mcu.kicad_sch")
		(attr smd)
		(fp_line
			(start -0.8 -0.45)
			(end -0.8 0.45)
			(stroke
				(width 0.12)
				(type solid)
			)
			(layer "F.SilkS")
		)
		(fp_line
			(start 0.8 -0.45)
			(end 0.8 0.45)
			(stroke
				(width 0.12)
				(type solid)
			)
			(layer "F.SilkS")
		)
		(fp_rect
			(start -0.898 -0.66)
			(end 0.898 0.65)
			(stroke
				(width 0.05)
				(type solid)
			)
			(fill no)
			(layer "F.CrtYd")
		)
		(pad "1" smd roundrect
			(at -0.6 0.298)
			(size 0.2 0.4)
			(layers "F.Cu" "F.Mask" "F.Paste")
			(roundrect_rratio 0.25)
			(net 355 "unconnected-(R24-R1.1-Pad1)")
			(pinfunction "R1.1")
			(pintype "passive+no_connect")
		)
		(pad "2" smd roundrect
			(at -0.202 0.298)
			(size 0.2 0.4)
			(layers "F.Cu" "F.Mask" "F.Paste")
			(roundrect_rratio 0.25)
			(net 1076 "/Supervisior MCU/USB_A15")
			(pinfunction "R2.1")
			(pintype "passive")
		)
		(pad "3" smd roundrect
			(at 0.2 0.298)
			(size 0.2 0.4)
			(layers "F.Cu" "F.Mask" "F.Paste")
			(roundrect_rratio 0.25)
			(net 1078 "/Supervisior MCU/USB_A17")
			(pinfunction "R3.1")
			(pintype "passive")
		)
		(pad "4" smd roundrect
			(at 0.598 0.298)
			(size 0.2 0.4)
			(layers "F.Cu" "F.Mask" "F.Paste")
			(roundrect_rratio 0.25)
			(net 1067 "/Supervisior MCU/USB_A6")
			(pinfunction "R4.1")
			(pintype "passive")
		)
		(pad "5" smd roundrect
			(at 0.598 -0.3)
			(size 0.2 0.4)
			(layers "F.Cu" "F.Mask" "F.Paste")
			(roundrect_rratio 0.25)
			(net 1362 "/SUP_MCU.A6")
			(pinfunction "R4.2")
			(pintype "passive")
		)
		(pad "6" smd roundrect
			(at 0.2 -0.3)
			(size 0.2 0.4)
			(layers "F.Cu" "F.Mask" "F.Paste")
			(roundrect_rratio 0.25)
			(net 1363 "/SUP_MCU.A17")
			(pinfunction "R3.2")
			(pintype "passive")
		)
		(pad "7" smd roundrect
			(at -0.202 -0.3)
			(size 0.2 0.4)
			(layers "F.Cu" "F.Mask" "F.Paste")
			(roundrect_rratio 0.25)
			(net 1364 "/SUP_MCU.A15")
			(pinfunction "R2.2")
			(pintype "passive")
		)
		(pad "8" smd roundrect
			(at -0.6 -0.3)
			(size 0.2 0.4)
			(layers "F.Cu" "F.Mask" "F.Paste")
			(roundrect_rratio 0.25)
			(net 356 "unconnected-(R24-R1.2-Pad8)")
			(pinfunction "R1.2")
			(pintype "passive+no_connect")
		)
	)
	(footprint "antmicro-footprints:HDMI-A_Receptacle_TE_2007435-1"
		(layer "F.Cu")
		(at 261.75 113.5 90)
		(property "Reference" "J16"
			(at 3.73 -7.3 180)
			(layer "F.SilkS")
			(effects
				(font
					(size 0.7 0.7)
					(thickness 0.15)
				)
				(justify left bottom)
			)
		)
		(property "Value" "HDMI-A_TE_2007435-1"
			(at 0 11.7 90)
			(layer "F.Fab")
			(effects
				(font
					(size 0.7 0.7)
					(thickness 0.15)
				)
				(justify left bottom)
			)
		)
		(property "Description" "HDMI Receptacle Connector 19 Position Panel Mount, Through Hole, Right Angle"
			(at 0 0 90)
			(layer "F.Fab")
			(hide yes)
			(effects
				(font
					(size 1.27 1.27)
					(thickness 0.15)
				)
			)
		)
		(property "Author" "Antmicro"
			(at 375.25 -148.25 0)
			(layer "F.Fab")
			(hide yes)
			(effects
				(font
					(size 1 1)
					(thickness 0.15)
				)
			)
		)
		(property "License" "Apache-2.0"
			(at 375.25 -148.25 0)
			(layer "F.Fab")
			(hide yes)
			(effects
				(font
					(size 1 1)
					(thickness 0.15)
				)
			)
		)
		(property "MPN" "2007435-1"
			(at 375.25 -148.25 0)
			(layer "F.Fab")
			(hide yes)
			(effects
				(font
					(size 1 1)
					(thickness 0.15)
				)
			)
		)
		(property "Manufacturer" "TE Connectivity"
			(at 375.25 -148.25 0)
			(layer "F.Fab")
			(hide yes)
			(effects
				(font
					(size 1 1)
					(thickness 0.15)
				)
			)
		)
		(sheetname "HDMI + Ethernet")
		(sheetfile "hdmi-ethernet.kicad_sch")
		(attr through_hole)
		(fp_line
			(start -4.351 -12.702)
			(end 1.85 -12.702)
			(stroke
				(width 0.15)
				(type solid)
			)
			(layer "F.SilkS")
		)
		(fp_line
			(start -4.351 -12.702)
			(end -4.351 -9.85)
			(stroke
				(width 0.15)
				(type solid)
			)
			(layer "F.SilkS")
		)
		(fp_line
			(start 3.35 -9.35)
			(end 3.35 -3.75)
			(stroke
				(width 0.15)
				(type solid)
			)
			(layer "F.SilkS")
		)
		(fp_line
			(start -4.351 -6.601)
			(end -4.351 -1.151)
			(stroke
				(width 0.15)
				(type solid)
			)
			(layer "F.SilkS")
		)
		(fp_line
			(start -4.351 2.749)
			(end -4.351 9.4)
			(stroke
				(width 0.15)
				(type solid)
			)
			(layer "F.SilkS")
		)
		(fp_line
			(start 3.35 9.4)
			(end 3.35 -0.103)
			(stroke
				(width 0.15)
				(type solid)
			)
			(layer "F.SilkS")
		)
		(fp_rect
			(start -4.641 -13.127)
			(end 3.638 10.749)
			(stroke
				(width 0.05)
				(type solid)
			)
			(fill no)
			(layer "F.CrtYd")
		)
		(pad "" np_thru_hole circle
			(at -2.5 -11.35 90)
			(size 1.7 1.7)
			(drill 1.7)
			(layers "F&B.Cu" "*.Mask")
		)
		(pad "" np_thru_hole circle
			(at 0.996 1.896 90)
			(size 1.7 1.7)
			(drill 1.7)
			(layers "F&B.Cu" "*.Mask")
		)
		(pad "1" thru_hole rect
			(at 0 0 90)
			(size 0.8 0.8)
			(drill 0.45)
			(layers "*.Cu" "*.Mask")
			(remove_unused_layers no)
			(net 867 "/HDMI + Ethernet/HDMI_CONN_D2_P")
			(pinfunction "D2+")
			(pintype "bidirectional")
		)
		(pad "2" thru_hole circle
			(at -1 -0.578 90)
			(size 0.8 0.8)
			(drill 0.45)
			(layers "*.Cu" "*.Mask")
			(remove_unused_layers no)
			(net 1 "GND")
			(pinfunction "D2S")
			(pintype "passive")
		)
		(pad "3" thru_hole circle
			(at 0 -1.156 90)
			(size 0.8 0.8)
			(drill 0.45)
			(layers "*.Cu" "*.Mask")
			(remove_unused_layers no)
			(net 866 "/HDMI + Ethernet/HDMI_CONN_D2_N")
			(pinfunction "D2-")
			(pintype "bidirectional")
		)
		(pad "4" thru_hole circle
			(at -1 -1.734 90)
			(size 0.8 0.8)
			(drill 0.45)
			(layers "*.Cu" "*.Mask")
			(remove_unused_layers no)
			(net 865 "/HDMI + Ethernet/HDMI_CONN_D1_P")
			(pinfunction "D1+")
			(pintype "bidirectional")
		)
		(pad "5" thru_hole circle
			(at 0 -2.311 90)
			(size 0.8 0.8)
			(drill 0.45)
			(layers "*.Cu" "*.Mask")
			(remove_unused_layers no)
			(net 1 "GND")
			(pinfunction "D1S")
			(pintype "passive")
		)
		(pad "6" thru_hole circle
			(at -1 -2.888 90)
			(size 0.8 0.8)
			(drill 0.45)
			(layers "*.Cu" "*.Mask")
			(remove_unused_layers no)
			(net 864 "/HDMI + Ethernet/HDMI_CONN_D1_N")
			(pinfunction "D1-")
			(pintype "bidirectional")
		)
		(pad "7" thru_hole circle
			(at 0 -3.465 90)
			(size 0.8 0.8)
			(drill 0.45)
			(layers "*.Cu" "*.Mask")
			(remove_unused_layers no)
			(net 863 "/HDMI + Ethernet/HDMI_CONN_D0_P")
			(pinfunction "D0+")
			(pintype "bidirectional")
		)
		(pad "8" thru_hole circle
			(at -1 -4.045 90)
			(size 0.8 0.8)
			(drill 0.45)
			(layers "*.Cu" "*.Mask")
			(remove_unused_layers no)
			(net 1 "GND")
			(pinfunction "D0S")
			(pintype "passive")
		)
		(pad "9" thru_hole circle
			(at 0 -4.622 90)
			(size 0.8 0.8)
			(drill 0.45)
			(layers "*.Cu" "*.Mask")
			(remove_unused_layers no)
			(net 862 "/HDMI + Ethernet/HDMI_CONN_D0_N")
			(pinfunction "D0-")
			(pintype "bidirectional")
		)
		(pad "10" thru_hole circle
			(at -1 -5.199 90)
			(size 0.8 0.8)
			(drill 0.45)
			(layers "*.Cu" "*.Mask")
			(remove_unused_layers no)
			(net 861 "/HDMI + Ethernet/HDMI_CONN_CLK_P")
			(pinfunction "CK+")
			(pintype "bidirectional")
		)
		(pad "11" thru_hole circle
			(at 0 -5.776 90)
			(size 0.8 0.8)
			(drill 0.45)
			(layers "*.Cu" "*.Mask")
			(remove_unused_layers no)
			(net 1 "GND")
			(pinfunction "CKS")
			(pintype "passive")
		)
		(pad "12" thru_hole circle
			(at -1 -6.353 90)
			(size 0.8 0.8)
			(drill 0.45)
			(layers "*.Cu" "*.Mask")
			(remove_unused_layers no)
			(net 868 "/HDMI + Ethernet/HDMI_CONN_CLK_N")
			(pinfunction "CK-")
			(pintype "bidirectional")
		)
		(pad "13" thru_hole circle
			(at 0 -6.93 90)
			(size 0.8 0.8)
			(drill 0.45)
			(layers "*.Cu" "*.Mask")
			(remove_unused_layers no)
			(net 42 "unconnected-(J16-CEC-Pad13)")
			(pinfunction "CEC")
			(pintype "bidirectional+no_connect")
		)
		(pad "14" thru_hole circle
			(at -1 -7.508 90)
			(size 0.8 0.8)
			(drill 0.45)
			(layers "*.Cu" "*.Mask")
			(remove_unused_layers no)
			(net 44 "unconnected-(J16-UTILITY{slash}HEAC+-Pad14)")
			(pinfunction "UTILITY/HEAC+")
			(pintype "bidirectional+no_connect")
		)
		(pad "15" thru_hole circle
			(at 0 -8.087 90)
			(size 0.8 0.8)
			(drill 0.45)
			(layers "*.Cu" "*.Mask")
			(remove_unused_layers no)
			(net 47 "unconnected-(J16-SCL-Pad15)")
			(pinfunction "SCL")
			(pintype "bidirectional+no_connect")
		)
		(pad "16" thru_hole circle
			(at -1 -8.664 90)
			(size 0.8 0.8)
			(drill 0.45)
			(layers "*.Cu" "*.Mask")
			(remove_unused_layers no)
			(net 48 "unconnected-(J16-SDA-Pad16)")
			(pinfunction "SDA")
			(pintype "bidirectional+no_connect")
		)
		(pad "17" thru_hole circle
			(at 0 -9.241 90)
			(size 0.8 0.8)
			(drill 0.45)
			(layers "*.Cu" "*.Mask")
			(remove_unused_layers no)
			(net 1 "GND")
			(pinfunction "GND")
			(pintype "power_in")
		)
		(pad "18" thru_hole circle
			(at -1 -9.818 90)
			(size 0.8 0.8)
			(drill 0.45)
			(layers "*.Cu" "*.Mask")
			(remove_unused_layers no)
			(net 794 "/HDMI + Ethernet/HDMI_CONN_5V")
			(pinfunction "+5V")
			(pintype "power_in")
		)
		(pad "19" thru_hole circle
			(at 0 -10.395 90)
			(size 0.8 0.8)
			(drill 0.45)
			(layers "*.Cu" "*.Mask")
			(remove_unused_layers no)
			(net 49 "unconnected-(J16-HPD{slash}HEAC--Pad19)")
			(pinfunction "HPD/HEAC-")
			(pintype "bidirectional+no_connect")
		)
		(pad "SH" thru_hole oval
			(at -3.75 -8.25 180)
			(size 3.5 1.7)
			(drill oval 2.5 0.9)
			(layers "*.Cu" "*.Mask")
			(remove_unused_layers no)
			(net 1 "GND")
			(pinfunction "SH")
			(pintype "passive")
		)
		(pad "SH" thru_hole oval
			(at -3.75 0.746 180)
			(size 3.5 1.7)
			(drill oval 2.5 0.9)
			(layers "*.Cu" "*.Mask")
			(remove_unused_layers no)
			(net 1 "GND")
			(pinfunction "SH")
			(pintype "passive")
		)
		(pad "SH" thru_hole oval
			(at 2.749 -11.35 180)
			(size 3.5 1.7)
			(drill oval 2.5 0.9)
			(layers "*.Cu" "*.Mask")
			(remove_unused_layers no)
			(net 1 "GND")
			(pinfunction "SH")
			(pintype "passive")
		)
		(pad "SH" thru_hole oval
			(at 2.749 -1.851 180)
			(size 3.5 1.7)
			(drill oval 2.5 0.9)
			(layers "*.Cu" "*.Mask")
			(remove_unused_layers no)
			(net 1 "GND")
			(pinfunction "SH")
			(pintype "passive")
		)
	)
	(footprint "antmicro-footprints:C_0402_1005Metric"
		(layer "F.Cu")
		(at 159.8 153.76 90)
		(descr "Capacitor SMD 0402")
		(tags "capacitor SMD 0402")
		(property "Reference" "C361"
			(at 0.8 0.35 90)
			(layer "F.SilkS")
			(effects
				(font
					(size 0.7 0.7)
					(thickness 0.15)
				)
				(justify left bottom)
			)
		)
		(property "Value" "C_10u_0402"
			(at 0 1.4 90)
			(layer "F.Fab")
			(effects
				(font
					(size 0.7 0.7)
					(thickness 0.15)
				)
				(justify left bottom)
			)
		)
		(property "Description" "SMD Multilayer Ceramic Capacitor, 10 µF, 6.3 V, 0402 [1005 Metric], ± 20%, X5R, CC Series"
			(at 0 0 90)
			(layer "F.Fab")
			(hide yes)
			(effects
				(font
					(size 1.27 1.27)
					(thickness 0.15)
				)
			)
		)
		(property "Author" "Antmicro"
			(at 313.56 -6.04 0)
			(layer "F.Fab")
			(hide yes)
			(effects
				(font
					(size 1 1)
					(thickness 0.15)
				)
			)
		)
		(property "Dielectric" ""
			(at 313.56 -6.04 0)
			(layer "F.Fab")
			(hide yes)
			(effects
				(font
					(size 1 1)
					(thickness 0.15)
				)
			)
		)
		(property "License" "Apache-2.0"
			(at 313.56 -6.04 0)
			(layer "F.Fab")
			(hide yes)
			(effects
				(font
					(size 1 1)
					(thickness 0.15)
				)
			)
		)
		(property "MPN" "CC0402MRX5R5BB106"
			(at 313.56 -6.04 0)
			(layer "F.Fab")
			(hide yes)
			(effects
				(font
					(size 1 1)
					(thickness 0.15)
				)
			)
		)
		(property "Manufacturer" "YAGEO"
			(at 313.56 -6.04 0)
			(layer "F.Fab")
			(hide yes)
			(effects
				(font
					(size 1 1)
					(thickness 0.15)
				)
			)
		)
		(property "Val" "10u"
			(at 313.56 -6.04 0)
			(layer "F.Fab")
			(hide yes)
			(effects
				(font
					(size 1 1)
					(thickness 0.15)
				)
			)
		)
		(property "Voltage" ""
			(at 313.56 -6.04 0)
			(layer "F.Fab")
			(hide yes)
			(effects
				(font
					(size 1 1)
					(thickness 0.15)
				)
			)
		)
		(sheetname "DC-DC Converters")
		(sheetfile "dc-dc.kicad_sch")
		(attr smd)
		(fp_rect
			(start -0.925 -0.47)
			(end 0.925 0.47)
			(stroke
				(width 0.05)
				(type default)
			)
			(fill no)
			(layer "F.CrtYd")
		)
		(fp_line
			(start 0.504 -0.25)
			(end 0.504 0.248)
			(stroke
				(width 0.15)
				(type solid)
			)
			(layer "F.Fab")
		)
		(fp_line
			(start -0.494 -0.25)
			(end 0.504 -0.25)
			(stroke
				(width 0.15)
				(type solid)
			)
			(layer "F.Fab")
		)
		(fp_line
			(start 0.504 0.248)
			(end -0.494 0.248)
			(stroke
				(width 0.15)
				(type solid)
			)
			(layer "F.Fab")
		)
		(fp_line
			(start -0.494 0.248)
			(end -0.494 -0.25)
			(stroke
				(width 0.15)
				(type solid)
			)
			(layer "F.Fab")
		)
		(pad "1" smd roundrect
			(at -0.48 0 90)
			(size 0.59 0.64)
			(layers "F.Cu" "F.Mask" "F.Paste")
			(roundrect_rratio 0.25)
			(net 1 "GND")
			(pintype "passive")
		)
		(pad "2" smd roundrect
			(at 0.48 0 90)
			(size 0.59 0.64)
			(layers "F.Cu" "F.Mask" "F.Paste")
			(roundrect_rratio 0.25)
			(net 750 "/DC-DC Converters/VDDR_VTT")
			(pintype "passive")
		)
	)
)
